# T6G (Grand Teton) — schematic netlist excerpt (pin names and nets, part order shuffled) for the footprints in the layout excerpt that follows; sources: Cadence DE-HDL packaged netlist, KiCad conversion of 04192023_DAF0TMB3IC0_F0TG_MB_C_brd_V02_OCP.brd

R4093  Q_RES  1K 1% CHIP  pkg 0402LF  page 236 : A = P3V3_AUX ; B = E1S_0_P3V3_ADC_ALERT_R
PC355_3  Q_CAP  22UF 4V 20% X6S  pkg C0805  page 216 : A = PVDDCR_SOC_P1 ; B = GND
C396  Q_CAP  0.1UF 10V 10% X7S  pkg C0201  page 345 : A = P0V9_CPU1_RT2_2A_2D ; B = GND

(kicad_pcb
	(version 20260206)
	(generator "pcbnew")
	(generator_version "10.0")
	(general
		(thickness 1.6)
		(legacy_teardrops no)
	)
	(paper "A4")
	(title_block
		(title "04192023_DAF0TMB3IC0_F0TG_MB_C_brd_V02_OCP.brd")
		(comment 1 "Grand Teton / footprints 7435-7437 of 8354")
	)
	(layers
		(0 "F.Cu" signal "TOP")
		(4 "In1.Cu" signal "GND")
		(6 "In2.Cu" signal "IN1")
		(8 "In3.Cu" signal "GND1")
		(10 "In4.Cu" signal "IN2")
		(12 "In5.Cu" signal "GND2")
		(14 "In6.Cu" signal "IN3")
		(16 "In7.Cu" signal "GND3")
		(18 "In8.Cu" signal "VCC")
		(20 "In9.Cu" signal "VCC1")
		(22 "In10.Cu" signal "GND4")
		(24 "In11.Cu" signal "IN4")
		(26 "In12.Cu" signal "GND5")
		(28 "In13.Cu" signal "IN5")
		(30 "In14.Cu" signal "GND6")
		(32 "In15.Cu" signal "IN6")
		(34 "In16.Cu" signal "GND7")
		(2 "B.Cu" signal "BOTTOM")
		(9 "F.Adhes" user "F.Adhesive")
		(11 "B.Adhes" user "B.Adhesive")
		(13 "F.Paste" user "Package Geometry/Pastemask Top")
		(15 "B.Paste" user "Package Geometry/Pastemask Bottom")
		(5 "F.SilkS" user "Ref Des/Silkscreen Top")
		(7 "B.SilkS" user "Ref Des/Silkscreen Bottom")
		(1 "F.Mask" user "Board Geometry/Soldermask Top")
		(3 "B.Mask" user "Board Geometry/Soldermask Bottom")
		(17 "Dwgs.User" user "User.Drawings")
		(19 "Cmts.User" user "User.Comments")
		(21 "Eco1.User" user "User.Eco1")
		(23 "Eco2.User" user "User.Eco2")
		(25 "Edge.Cuts" user "Board Geometry/Outline")
		(27 "Margin" user)
		(31 "F.CrtYd" user "Package Geometry/Place Bound Top")
		(29 "B.CrtYd" user "Package Geometry/Place Bound Bottom")
		(35 "F.Fab" user "Ref Des/Assembly Top")
		(33 "B.Fab" user "Ref Des/Assembly Bottom")
	)
	(footprint ""
		(layer "B.Cu")
		(at 151.946102 -388.011162 -90)
		(property "Reference" "C396"
			(at 0 0 90)
			(layer "B.SilkS")
			(hide yes)
			(effects
				(font
					(size 1.27 1.27)
				)
				(justify mirror)
			)
		)
		(property "Value" ""
			(at 0 0 90)
			(layer "B.Fab")
			(effects
				(font
					(size 1.27 1.27)
				)
				(justify mirror)
			)
		)
		(duplicate_pad_numbers_are_jumpers no)
		(fp_line
			(start -0.299974 0.150114)
			(end 0.299974 0.150114)
			(stroke
				(width 0.1)
				(type default)
			)
			(layer "B.Fab")
		)
		(fp_line
			(start 0.299974 0.150114)
			(end 0.299974 -0.150114)
			(stroke
				(width 0.1)
				(type default)
			)
			(layer "B.Fab")
		)
		(fp_line
			(start -0.299974 -0.150114)
			(end -0.299974 0.150114)
			(stroke
				(width 0.1)
				(type default)
			)
			(layer "B.Fab")
		)
		(fp_line
			(start 0.299974 -0.150114)
			(end -0.299974 -0.150114)
			(stroke
				(width 0.1)
				(type default)
			)
			(layer "B.Fab")
		)
		(pad "1" smd rect
			(at 0.2667 0 90)
			(size 0.3048 0.381)
			(layers "B.Cu" "B.Mask" "B.Paste")
			(net "P0V9_CPU1_RT2_2A_2D")
		)
		(pad "2" smd rect
			(at -0.2667 0 90)
			(size 0.3048 0.381)
			(layers "B.Cu" "B.Mask" "B.Paste")
			(net "GND")
		)
	)
	(footprint ""
		(layer "B.Cu")
		(at 135.115554 -165.145212 90)
		(property "Reference" "PC355_3"
			(at 0 0 90)
			(layer "B.SilkS")
			(hide yes)
			(effects
				(font
					(size 1.27 1.27)
				)
				(justify mirror)
			)
		)
		(property "Value" ""
			(at 0 0 90)
			(layer "B.Fab")
			(effects
				(font
					(size 1.27 1.27)
				)
				(justify mirror)
			)
		)
		(duplicate_pad_numbers_are_jumpers no)
		(fp_line
			(start 1.524 -0.762)
			(end -1.524 -0.762)
			(stroke
				(width 0.1524)
				(type default)
			)
			(layer "B.SilkS")
		)
		(fp_line
			(start -1.524 -0.762)
			(end -1.524 0.762)
			(stroke
				(width 0.1524)
				(type default)
			)
			(layer "B.SilkS")
		)
		(fp_line
			(start 1.524 0.762)
			(end 1.524 -0.762)
			(stroke
				(width 0.1524)
				(type default)
			)
			(layer "B.SilkS")
		)
		(fp_line
			(start -1.524 0.762)
			(end 1.524 0.762)
			(stroke
				(width 0.1524)
				(type default)
			)
			(layer "B.SilkS")
		)
		(fp_line
			(start 1.1049 -0.724916)
			(end 1.1049 0.724916)
			(stroke
				(width 0.1)
				(type default)
			)
			(layer "B.Fab")
		)
		(fp_line
			(start -1.1049 -0.724916)
			(end 1.1049 -0.724916)
			(stroke
				(width 0.1)
				(type default)
			)
			(layer "B.Fab")
		)
		(fp_line
			(start 1.1049 0.724916)
			(end -1.1049 0.724916)
			(stroke
				(width 0.1)
				(type default)
			)
			(layer "B.Fab")
		)
		(fp_line
			(start -1.1049 0.724916)
			(end -1.1049 -0.724916)
			(stroke
				(width 0.1)
				(type default)
			)
			(layer "B.Fab")
		)
		(pad "1" smd rect
			(at 0.889 0 90)
			(size 1.016 1.27)
			(layers "B.Cu" "B.Mask" "B.Paste")
			(net "PVDDCR_SOC_P1")
		)
		(pad "2" smd rect
			(at -0.889 0 90)
			(size 1.016 1.27)
			(layers "B.Cu" "B.Mask" "B.Paste")
			(net "GND")
		)
	)
	(footprint ""
		(layer "B.Cu")
		(at 212.725 -57.061608 90)
		(property "Reference" "R4093"
			(at 0 0 90)
			(layer "B.SilkS")
			(hide yes)
			(effects
				(font
					(size 1.27 1.27)
				)
				(justify mirror)
			)
		)
		(property "Value" ""
			(at 0 0 90)
			(layer "B.Fab")
			(effects
				(font
					(size 1.27 1.27)
				)
				(justify mirror)
			)
		)
		(duplicate_pad_numbers_are_jumpers no)
		(fp_line
			(start 0.7874 -0.4064)
			(end -0.7874 -0.4064)
			(stroke
				(width 0.1524)
				(type default)
			)
			(layer "B.SilkS")
		)
		(fp_line
			(start -0.7874 -0.4064)
			(end -0.7874 0.4064)
			(stroke
				(width 0.1524)
				(type default)
			)
			(layer "B.SilkS")
		)
		(fp_line
			(start 0.7874 0.4064)
			(end 0.7874 -0.4064)
			(stroke
				(width 0.1524)
				(type default)
			)
			(layer "B.SilkS")
		)
		(fp_line
			(start -0.7874 0.4064)
			(end 0.7874 0.4064)
			(stroke
				(width 0.1524)
				(type default)
			)
			(layer "B.SilkS")
		)
		(fp_line
			(start 0.67945 -0.305054)
			(end 0.12065 -0.305054)
			(stroke
				(width 0.1)
				(type default)
			)
			(layer "B.Fab")
		)
		(fp_line
			(start 0.12065 -0.305054)
			(end 0.12065 -0.2794)
			(stroke
				(width 0.1)
				(type default)
			)
			(layer "B.Fab")
		)
		(fp_line
			(start -0.12065 -0.3048)
			(end -0.67945 -0.3048)
			(stroke
				(width 0.1)
				(type default)
			)
			(layer "B.Fab")
		)
		(fp_line
			(start -0.67945 -0.3048)
			(end -0.67945 0.3048)
			(stroke
				(width 0.1)
				(type default)
			)
			(layer "B.Fab")
		)
		(fp_line
			(start 0.12065 -0.2794)
			(end -0.12065 -0.2794)
			(stroke
				(width 0.1)
				(type default)
			)
			(layer "B.Fab")
		)
		(fp_line
			(start -0.12065 -0.2794)
			(end -0.12065 -0.3048)
			(stroke
				(width 0.1)
				(type default)
			)
			(layer "B.Fab")
		)
		(fp_line
			(start 0.12065 0.2794)
			(end 0.12065 0.3048)
			(stroke
				(width 0.1)
				(type default)
			)
			(layer "B.Fab")
		)
		(fp_line
			(start -0.120396 0.2794)
			(end 0.12065 0.2794)
			(stroke
				(width 0.1)
				(type default)
			)
			(layer "B.Fab")
		)
		(fp_line
			(start 0.67945 0.3048)
			(end 0.67945 -0.305054)
			(stroke
				(width 0.1)
				(type default)
			)
			(layer "B.Fab")
		)
		(fp_line
			(start 0.12065 0.3048)
			(end 0.67945 0.3048)
			(stroke
				(width 0.1)
				(type default)
			)
			(layer "B.Fab")
		)
		(fp_line
			(start -0.120396 0.3048)
			(end -0.120396 0.2794)
			(stroke
				(width 0.1)
				(type default)
			)
			(layer "B.Fab")
		)
		(fp_line
			(start -0.67945 0.3048)
			(end -0.120396 0.3048)
			(stroke
				(width 0.1)
				(type default)
			)
			(layer "B.Fab")
		)
		(pad "1" smd circle
			(at 0.40005 0 270)
			(size 0 0)
			(layers "B.Cu" "B.Mask" "B.Paste")
			(net "P3V3_AUX")
		)
		(pad "2" smd circle
			(at -0.40005 0 270)
			(size 0 0)
			(layers "B.Cu" "B.Mask" "B.Paste")
			(net "E1S_0_P3V3_ADC_ALERT_R")
		)
	)
)
